# T6G (Grand Teton) — schematic netlist excerpt (pin names and nets, part order shuffled) for the footprints in the layout excerpt that follows; sources: Cadence DE-HDL packaged netlist, KiCad conversion of 04192023_DAF0TMB3IC0_F0TG_MB_C_brd_V02_OCP.brd

U22  TCA9548APWR  IC  pkg TSSOP24XA  page 185
  A0  = RT_ROM_SMB_MUX_ADDR0
  A1  = RT_ROM_SMB_MUX_ADDR1
  \reset#\  = RST_SMB_RT_ROM_N
  SD0  = SMB_RT_CPU1_P0_ROM_MUX_2D_R_SDA
  SC0  = SMB_RT_CPU1_P0_ROM_MUX_2D_R_SCL
  SD1  = SMB_RT_CPU1_P1_ROM_MUX_2D_R_SDA
  SC1  = SMB_RT_CPU1_P1_ROM_MUX_2D_R_SCL
  SD2  = SMB_RT_CPU1_P3_ROM_MUX_2D_R_SDA
  SC2  = SMB_RT_CPU1_P3_ROM_MUX_2D_R_SCL
  SD3  = SMB_RT_CPU1_P2_ROM_MUX_2D_R_SDA
  SC3  = SMB_RT_CPU1_P2_ROM_MUX_2D_R_SCL
  GND  = GND
  SD4  = SMB_RT_CPU0_P0_ROM_MUX_2D_R_SDA
  SC4  = SMB_RT_CPU0_P0_ROM_MUX_2D_R_SCL
  SD5  = SMB_RT_CPU0_P1_ROM_MUX_2D_R_SDA
  SC5  = SMB_RT_CPU0_P1_ROM_MUX_2D_R_SCL
  SD6  = SMB_RT_CPU0_P3_ROM_MUX_2D_R_SDA
  SC6  = SMB_RT_CPU0_P3_ROM_MUX_2D_R_SCL
  SD7  = SMB_RT_CPU0_P2_ROM_MUX_2D_R_SDA
  SC7  = SMB_RT_CPU0_P2_ROM_MUX_2D_R_SCL
  A2  = RT_ROM_SMB_MUX_ADDR2
  SCL  = SMB_MUX_RT_ROM_SCL
  SDA  = SMB_MUX_RT_ROM_SDA
  VCC  = P1V8_AUX

(kicad_pcb
	(version 20260206)
	(generator "pcbnew")
	(generator_version "10.0")
	(general
		(thickness 1.6)
		(legacy_teardrops no)
	)
	(paper "A4")
	(title_block
		(title "04192023_DAF0TMB3IC0_F0TG_MB_C_brd_V02_OCP.brd")
		(comment 1 "Grand Teton / footprints 4941-4941 of 8354")
	)
	(layers
		(0 "F.Cu" signal "TOP")
		(4 "In1.Cu" signal "GND")
		(6 "In2.Cu" signal "IN1")
		(8 "In3.Cu" signal "GND1")
		(10 "In4.Cu" signal "IN2")
		(12 "In5.Cu" signal "GND2")
		(14 "In6.Cu" signal "IN3")
		(16 "In7.Cu" signal "GND3")
		(18 "In8.Cu" signal "VCC")
		(20 "In9.Cu" signal "VCC1")
		(22 "In10.Cu" signal "GND4")
		(24 "In11.Cu" signal "IN4")
		(26 "In12.Cu" signal "GND5")
		(28 "In13.Cu" signal "IN5")
		(30 "In14.Cu" signal "GND6")
		(32 "In15.Cu" signal "IN6")
		(34 "In16.Cu" signal "GND7")
		(2 "B.Cu" signal "BOTTOM")
		(9 "F.Adhes" user "F.Adhesive")
		(11 "B.Adhes" user "B.Adhesive")
		(13 "F.Paste" user "Package Geometry/Pastemask Top")
		(15 "B.Paste" user "Package Geometry/Pastemask Bottom")
		(5 "F.SilkS" user "Ref Des/Silkscreen Top")
		(7 "B.SilkS" user "Ref Des/Silkscreen Bottom")
		(1 "F.Mask" user "Board Geometry/Soldermask Top")
		(3 "B.Mask" user "Board Geometry/Soldermask Bottom")
		(17 "Dwgs.User" user "User.Drawings")
		(19 "Cmts.User" user "User.Comments")
		(21 "Eco1.User" user "User.Eco1")
		(23 "Eco2.User" user "User.Eco2")
		(25 "Edge.Cuts" user "Board Geometry/Outline")
		(27 "Margin" user)
		(31 "F.CrtYd" user "Package Geometry/Place Bound Top")
		(29 "B.CrtYd" user "Package Geometry/Place Bound Bottom")
		(35 "F.Fab" user "Ref Des/Assembly Top")
		(33 "B.Fab" user "Ref Des/Assembly Bottom")
	)
	(footprint ""
		(layer "B.Cu")
		(at 247.264682 -336.846164 180)
		(property "Reference" "U22"
			(at -1.699768 -5.606796 0)
			(unlocked yes)
			(layer "B.SilkS")
			(effects
				(font
					(size 0.7874 0.5842)
					(thickness 0.1524)
				)
				(justify left mirror)
			)
		)
		(property "Value" ""
			(at 0 0 0)
			(layer "B.Fab")
			(effects
				(font
					(size 1.27 1.27)
				)
				(justify mirror)
			)
		)
		(duplicate_pad_numbers_are_jumpers no)
		(fp_line
			(start 1.8542 3.949954)
			(end -1.8542 3.949954)
			(stroke
				(width 0.1524)
				(type default)
			)
			(layer "B.SilkS")
		)
		(fp_line
			(start 1.8542 -3.949954)
			(end 1.8542 3.949954)
			(stroke
				(width 0.1524)
				(type default)
			)
			(layer "B.SilkS")
		)
		(fp_line
			(start 1.282954 -3.949954)
			(end 1.8542 -3.949954)
			(stroke
				(width 0.1524)
				(type default)
			)
			(layer "B.SilkS")
		)
		(fp_line
			(start 0 -2.667)
			(end 1.282954 -3.949954)
			(stroke
				(width 0.1524)
				(type default)
			)
			(layer "B.SilkS")
		)
		(fp_line
			(start -1.282954 -3.949954)
			(end 0 -2.667)
			(stroke
				(width 0.1524)
				(type default)
			)
			(layer "B.SilkS")
		)
		(fp_line
			(start -1.8542 3.949954)
			(end -1.8542 -3.949954)
			(stroke
				(width 0.1524)
				(type default)
			)
			(layer "B.SilkS")
		)
		(fp_line
			(start -1.8542 -3.949954)
			(end -1.282954 -3.949954)
			(stroke
				(width 0.1524)
				(type default)
			)
			(layer "B.SilkS")
		)
		(fp_poly
			(pts
				(xy 2.334514 -5.227066) (xy 3.348482 -5.29209) (xy 2.906522 -4.24561)
			)
			(stroke
				(width 0)
				(type default)
			)
			(fill yes)
			(layer "B.SilkS")
		)
		(fp_line
			(start 2.249932 3.949954)
			(end -2.249932 3.949954)
			(stroke
				(width 0.1)
				(type default)
			)
			(layer "B.Fab")
		)
		(fp_line
			(start 2.249932 -3.949954)
			(end 2.249932 3.949954)
			(stroke
				(width 0.1)
				(type default)
			)
			(layer "B.Fab")
		)
		(fp_line
			(start -2.249932 3.949954)
			(end -2.249932 -3.949954)
			(stroke
				(width 0.1)
				(type default)
			)
			(layer "B.Fab")
		)
		(fp_line
			(start -2.249932 -3.949954)
			(end 2.249932 -3.949954)
			(stroke
				(width 0.1)
				(type default)
			)
			(layer "B.Fab")
		)
		(fp_poly
			(pts
				(xy 4.8006 -4.08305) (xy 4.8006 -3.06705) (xy 3.7846 -3.57505)
			)
			(stroke
				(width 0)
				(type default)
			)
			(fill yes)
			(layer "B.Fab")
		)
		(pad "1" smd rect
			(at 2.800096 -3.57505 90)
			(size 0.3048 1.6002)
			(layers "B.Cu" "B.Mask" "B.Paste")
			(net "RT_ROM_SMB_MUX_ADDR0")
		)
		(pad "2" smd rect
			(at 2.800096 -2.925064 90)
			(size 0.3048 1.6002)
			(layers "B.Cu" "B.Mask" "B.Paste")
			(net "RT_ROM_SMB_MUX_ADDR1")
		)
		(pad "3" smd rect
			(at 2.800096 -2.275078 90)
			(size 0.3048 1.6002)
			(layers "B.Cu" "B.Mask" "B.Paste")
			(net "RST_SMB_RT_ROM_N")
		)
		(pad "4" smd rect
			(at 2.800096 -1.625092 90)
			(size 0.3048 1.6002)
			(layers "B.Cu" "B.Mask" "B.Paste")
			(net "SMB_RT_CPU1_P0_ROM_MUX_2D_R_SDA")
		)
		(pad "5" smd rect
			(at 2.800096 -0.975106 90)
			(size 0.3048 1.6002)
			(layers "B.Cu" "B.Mask" "B.Paste")
			(net "SMB_RT_CPU1_P0_ROM_MUX_2D_R_SCL")
		)
		(pad "6" smd rect
			(at 2.800096 -0.32512 90)
			(size 0.3048 1.6002)
			(layers "B.Cu" "B.Mask" "B.Paste")
			(net "SMB_RT_CPU1_P1_ROM_MUX_2D_R_SDA")
		)
		(pad "7" smd rect
			(at 2.800096 0.32512 90)
			(size 0.3048 1.6002)
			(layers "B.Cu" "B.Mask" "B.Paste")
			(net "SMB_RT_CPU1_P1_ROM_MUX_2D_R_SCL")
		)
		(pad "8" smd rect
			(at 2.800096 0.975106 90)
			(size 0.3048 1.6002)
			(layers "B.Cu" "B.Mask" "B.Paste")
			(net "SMB_RT_CPU1_P3_ROM_MUX_2D_R_SDA")
		)
		(pad "9" smd rect
			(at 2.800096 1.625092 90)
			(size 0.3048 1.6002)
			(layers "B.Cu" "B.Mask" "B.Paste")
			(net "SMB_RT_CPU1_P3_ROM_MUX_2D_R_SCL")
		)
		(pad "10" smd rect
			(at 2.800096 2.275078 90)
			(size 0.3048 1.6002)
			(layers "B.Cu" "B.Mask" "B.Paste")
			(net "SMB_RT_CPU1_P2_ROM_MUX_2D_R_SDA")
		)
		(pad "11" smd rect
			(at 2.800096 2.925064 90)
			(size 0.3048 1.6002)
			(layers "B.Cu" "B.Mask" "B.Paste")
			(net "SMB_RT_CPU1_P2_ROM_MUX_2D_R_SCL")
		)
		(pad "12" smd rect
			(at 2.800096 3.57505 90)
			(size 0.3048 1.6002)
			(layers "B.Cu" "B.Mask" "B.Paste")
			(net "GND")
		)
		(pad "13" smd rect
			(at -2.800096 3.57505 90)
			(size 0.3048 1.6002)
			(layers "B.Cu" "B.Mask" "B.Paste")
			(net "SMB_RT_CPU0_P0_ROM_MUX_2D_R_SDA")
		)
		(pad "14" smd rect
			(at -2.800096 2.925064 90)
			(size 0.3048 1.6002)
			(layers "B.Cu" "B.Mask" "B.Paste")
			(net "SMB_RT_CPU0_P0_ROM_MUX_2D_R_SCL")
		)
		(pad "15" smd rect
			(at -2.800096 2.275078 90)
			(size 0.3048 1.6002)
			(layers "B.Cu" "B.Mask" "B.Paste")
			(net "SMB_RT_CPU0_P1_ROM_MUX_2D_R_SDA")
		)
		(pad "16" smd rect
			(at -2.800096 1.625092 90)
			(size 0.3048 1.6002)
			(layers "B.Cu" "B.Mask" "B.Paste")
			(net "SMB_RT_CPU0_P1_ROM_MUX_2D_R_SCL")
		)
		(pad "17" smd rect
			(at -2.800096 0.975106 90)
			(size 0.3048 1.6002)
			(layers "B.Cu" "B.Mask" "B.Paste")
			(net "SMB_RT_CPU0_P3_ROM_MUX_2D_R_SDA")
		)
		(pad "18" smd rect
			(at -2.800096 0.32512 90)
			(size 0.3048 1.6002)
			(layers "B.Cu" "B.Mask" "B.Paste")
			(net "SMB_RT_CPU0_P3_ROM_MUX_2D_R_SCL")
		)
		(pad "19" smd rect
			(at -2.800096 -0.32512 90)
			(size 0.3048 1.6002)
			(layers "B.Cu" "B.Mask" "B.Paste")
			(net "SMB_RT_CPU0_P2_ROM_MUX_2D_R_SDA")
		)
		(pad "20" smd rect
			(at -2.800096 -0.975106 90)
			(size 0.3048 1.6002)
			(layers "B.Cu" "B.Mask" "B.Paste")
			(net "SMB_RT_CPU0_P2_ROM_MUX_2D_R_SCL")
		)
		(pad "21" smd rect
			(at -2.800096 -1.625092 90)
			(size 0.3048 1.6002)
			(layers "B.Cu" "B.Mask" "B.Paste")
			(net "RT_ROM_SMB_MUX_ADDR2")
		)
		(pad "22" smd rect
			(at -2.800096 -2.275078 90)
			(size 0.3048 1.6002)
			(layers "B.Cu" "B.Mask" "B.Paste")
			(net "SMB_MUX_RT_ROM_SCL")
		)
		(pad "23" smd rect
			(at -2.800096 -2.925064 90)
			(size 0.3048 1.6002)
			(layers "B.Cu" "B.Mask" "B.Paste")
			(net "SMB_MUX_RT_ROM_SDA")
		)
		(pad "24" smd rect
			(at -2.800096 -3.57505 90)
			(size 0.3048 1.6002)
			(layers "B.Cu" "B.Mask" "B.Paste")
			(net "P1V8_AUX")
		)
	)
)
